FILE_TYPE = CONNECTIVITY;
{Allegro Design Entry HDL 17.4-2019 S026 (4007227) 1/17/2022}
"PAGE_NUMBER" = 58;
0"NC";
1"GND\g";
2"GND\g";
3"GND\g";
4"GND\g";
5"GND\g";
6"GND\g";
7"GND\g";
8"GND\g";
9"GND\g";
10"GND\g";
11"GND\g";
12"GND\g";
%"GENOA_SP5"
"28","(-8575,3425)","0","pure_quanta","I1";
;
LOCATION"U26"
$SEC"28"
CDS_SEC"28"
PART_TYPE"SMLF"
MATERIAL"IO"
VALUE"SOCKET6096_13568-001"
CDS_LIB"pure_quanta"
CDS_LMAN_SYM_OUTLINE"-400,3050,400,-3050"
NEEDS_NO_SIZE"TRUE"
PART_NUMBER"DGA^6000030";
"VSS_H34"
$PN"H34"2;
"VSS_H31"
$PN"H31"2;
"VSS_H28"
$PN"H28"2;
"VSS_H25"
$PN"H25"2;
"VSS_H22"
$PN"H22"2;
"VSS_H17"
$PN"H17"2;
"VSS_H15"
$PN"H15"2;
"VSS_H10"
$PN"H10"2;
"VSS_H8"
$PN"H8"2;
"VSS_H3"
$PN"H3"2;
"VSS_G75"
$PN"G75"2;
"VSS_G72"
$PN"G72"2;
"VSS_G70"
$PN"G70"2;
"VSS_G68"
$PN"G68"2;
"VSS_G65"
$PN"G65"2;
"VSS_G63"
$PN"G63"2;
"VSS_G61"
$PN"G61"2;
"VSS_G58"
$PN"G58"2;
"VSS_G56"
$PN"G56"2;
"VSS_G54"
$PN"G54"2;
"VSS_G51"
$PN"G51"2;
"VSS_G48"
$PN"G48"2;
"VSS_G45"
$PN"G45"2;
"VSS_G42"
$PN"G42"2;
"VSS_G34"
$PN"G34"2;
"VSS_G31"
$PN"G31"2;
"VSS_G28"
$PN"G28"2;
"VSS_G25"
$PN"G25"2;
"VSS_G22"
$PN"G22"2;
"VSS_G20"
$PN"G20"2;
"VSS_G18"
$PN"G18"2;
"VSS_G15"
$PN"G15"2;
"VSS_G13"
$PN"G13"2;
"VSS_G11"
$PN"G11"2;
"VSS_G8"
$PN"G8"2;
"VSS_G6"
$PN"G6"2;
"VSS_G4"
$PN"G4"2;
"VSS_G1"
$PN"G1"2;
"VSS_F73"
$PN"F73"2;
"VSS_F71"
$PN"F71"2;
"VSS_F68"
$PN"F68"2;
"VSS_F66"
$PN"F66"2;
"VSS_F64"
$PN"F64"2;
"VSS_F61"
$PN"F61"2;
"VSS_F59"
$PN"F59"2;
"VSS_F57"
$PN"F57"2;
"VSS_F53"
$PN"F53"2;
"VSS_F52"
$PN"F52"2;
"VSS_F50"
$PN"F50"2;
"VSS_F49"
$PN"F49"2;
"VSS_F47"
$PN"F47"2;
"VSS_F46"
$PN"F46"2;
"VSS_F44"
$PN"F44"2;
"VSS_F43"
$PN"F43"2;
"VSS_F41"
$PN"F41"2;
"VSS_F40"
$PN"F40"2;
"VSS_F39"
$PN"F39"2;
"VSS_F37"
$PN"F37"2;
"VSS_F36"
$PN"F36"2;
"VSS_F35"
$PN"F35"2;
"VSS_F33"
$PN"F33"2;
"VSS_F32"
$PN"F32"2;
"VSS_F30"
$PN"F30"2;
"VSS_F29"
$PN"F29"2;
"VSS_F27"
$PN"F27"2;
"VSS_F26"
$PN"F26"2;
"VSS_F24"
$PN"F24"2;
"VSS_F23"
$PN"F23"2;
"VSS_F19"
$PN"F19"2;
"VSS_F17"
$PN"F17"2;
"VSS_F15"
$PN"F15"2;
"VSS_F12"
$PN"F12"2;
"VSS_F10"
$PN"F10"2;
"VSS_F8"
$PN"F8"2;
"VSS_F5"
$PN"F5"2;
"VSS_F3"
$PN"F3"2;
"VSS_E75"
$PN"E75"2;
"VSS_E73"
$PN"E73"2;
"VSS_E72"
$PN"E72"2;
"VSS_E70"
$PN"E70"2;
"VSS_E69"
$PN"E69"2;
"VSS_E68"
$PN"E68"2;
"VSS_E66"
$PN"E66"2;
"VSS_E65"
$PN"E65"2;
"VSS_E63"
$PN"E63"2;
"VSS_E62"
$PN"E62"2;
"VSS_E61"
$PN"E61"2;
"VSS_E59"
$PN"E59"2;
"VSS_E58"
$PN"E58"2;
"VSS_E56"
$PN"E56"2;
"VSS_E55"
$PN"E55"2;
"VSS_E53"
$PN"E53"2;
"VSS_E52"
$PN"E52"2;
"VSS_E21"
$PN"E21"2;
"VSS_E20"
$PN"E20"2;
"VSS_E18"
$PN"E18"2;
"VSS_E17"
$PN"E17"2;
"VSS_E15"
$PN"E15"2;
"VSS_E14"
$PN"E14"2;
"VSS_E13"
$PN"E13"2;
"VSS_E10"
$PN"E10"2;
"VSS_E8"
$PN"E8"3;
"VSS_E7"
$PN"E7"3;
"VSS_E6"
$PN"E6"3;
"VSS_E3"
$PN"E3"3;
"VSS_E1"
$PN"E1"3;
"VSS_D74"
$PN"D74"3;
"VSS_D73"
$PN"D73"3;
"VSS_D71"
$PN"D71"3;
"VSS_D70"
$PN"D70"3;
"VSS_D67"
$PN"D67"3;
"VSS_D66"
$PN"D66"3;
"VSS_D64"
$PN"D64"3;
"VSS_D63"
$PN"D63"3;
"VSS_D61"
$PN"D61"3;
"VSS_D60"
$PN"D60"3;
"VSS_D59"
$PN"D59"3;
"VSS_D57"
$PN"D57"3;
"VSS_D54"
$PN"D54"3;
"VSS_D53"
$PN"D53"3;
"VSS_D52"
$PN"D52"3;
"VSS_D51"
$PN"D51"3;
"VSS_D50"
$PN"D50"3;
"VSS_D49"
$PN"D49"3;
"VSS_D48"
$PN"D48"3;
"VSS_D47"
$PN"D47"3;
"VSS_D46"
$PN"D46"3;
"VSS_D45"
$PN"D45"3;
"VSS_D44"
$PN"D44"3;
"VSS_D43"
$PN"D43"3;
"VSS_D42"
$PN"D42"3;
"VSS_D41"
$PN"D41"3;
"VSS_D40"
$PN"D40"3;
"VSS_D39"
$PN"D39"3;
"VSS_D37"
$PN"D37"3;
"VSS_D35"
$PN"D35"3;
"VSS_D31"
$PN"D31"3;
"VSS_D30"
$PN"D30"3;
"VSS_D29"
$PN"D29"3;
"VSS_D28"
$PN"D28"3;
"VSS_D27"
$PN"D27"3;
"VSS_D26"
$PN"D26"3;
"VSS_D25"
$PN"D25"3;
"VSS_D24"
$PN"D24"3;
"VSS_D21"
$PN"D21"3;
"VSS_D20"
$PN"D20"3;
"VSS_D19"
$PN"D19"3;
"VSS_D17"
$PN"D17"3;
"VSS_D16"
$PN"D16"3;
"VSS_D13"
$PN"D13"3;
"VSS_D12"
$PN"D12"3;
"VSS_D10"
$PN"D10"3;
"VSS_D9"
$PN"D9"3;
"VSS_D6"
$PN"D6"3;
"VSS_D5"
$PN"D5"3;
"VSS_D3"
$PN"D3"3;
"VSS_D2"
$PN"D2"3;
"VSS_C75"
$PN"C75"3;
"VSS_C73"
$PN"C73"3;
"VSS_C71"
$PN"C71"3;
"VSS_C69"
$PN"C69"3;
"VSS_C67"
$PN"C67"3;
"VSS_C64"
$PN"C64"3;
"VSS_C61"
$PN"C61"3;
"VSS_C57"
$PN"C57"3;
"VSS_C56"
$PN"C56"3;
"VSS_C55"
$PN"C55"3;
"VSS_C52"
$PN"C52"3;
"VSS_C49"
$PN"C49"3;
"VSS_C46"
$PN"C46"3;
"VSS_C43"
$PN"C43"3;
"VSS_C40"
$PN"C40"3;
"VSS_C36"
$PN"C36"3;
"VSS_C30"
$PN"C30"3;
"VSS_C27"
$PN"C27"3;
"VSS_C24"
$PN"C24"3;
"VSS_C21"
$PN"C21"3;
"VSS_C15"
$PN"C15"3;
"VSS_C13"
$PN"C13"3;
"VSS_C11"
$PN"C11"3;
"VSS_C10"
$PN"C10"3;
"VSS_C8"
$PN"C8"3;
"VSS_C5"
$PN"C5"3;
"VSS_C1"
$PN"C1"3;
"VSS_B70"
$PN"B70"3;
"VSS_B68"
$PN"B68"3;
"VSS_B65"
$PN"B65"3;
"VSS_B62"
$PN"B62"3;
"VSS_B59"
$PN"B59"3;
"VSS_B55"
$PN"B55"3;
"VSS_B52"
$PN"B52"3;
"VSS_B49"
$PN"B49"3;
"VSS_B46"
$PN"B46"3;
"VSS_B43"
$PN"B43"3;
"VSS_B39"
$PN"B39"3;
"VSS_B37"
$PN"B37"3;
"VSS_B33"
$PN"B33"3;
"VSS_B30"
$PN"B30"3;
"VSS_B27"
$PN"B27"3;
"VSS_B24"
$PN"B24"3;
"VSS_B18"
$PN"B18"3;
"VSS_B13"
$PN"B13"3;
"VSS_B11"
$PN"B11"3;
"VSS_B10"
$PN"B10"3;
"VSS_B8"
$PN"B8"3;
"VSS_B7"
$PN"B7"3;
"VSS_A73"
$PN"A73"3;
"VSS_A72"
$PN"A72"3;
"VSS_A67"
$PN"A67"3;
"VSS_A61"
$PN"A61"3;
"VSS_A53"
$PN"A53"3;
"VSS_A49"
$PN"A49"3;
"VSS_A47"
$PN"A47"3;
"VSS_A44"
$PN"A44"3;
"VSS_A43"
$PN"A43"3;
"VSS_A27"
$PN"A27"3;
"VSS_A21"
$PN"A21"3;
"VSS_A15"
$PN"A15"3;
"VSS_A9"
$PN"A9"3;
"VSS_A3"
$PN"A3"3;
"VSS_J13"
$PN"J13"2;
"VSS_J11"
$PN"J11"2;
"VSS_J8"
$PN"J8"2;
"VSS_J6"
$PN"J6"2;
"VSS_J4"
$PN"J4"2;
"VSS_J1"
$PN"J1"2;
"VSS_H73"
$PN"H73"2;
"VSS_H68"
$PN"H68"2;
"VSS_H66"
$PN"H66"2;
"VSS_H61"
$PN"H61"2;
"VSS_H59"
$PN"H59"2;
"VSS_H54"
$PN"H54"2;
"VSS_H51"
$PN"H51"2;
"VSS_H48"
$PN"H48"2;
"VSS_H45"
$PN"H45"2;
"VSS_H42"
$PN"H42"2;
"VSS_H39"
$PN"H39"2;
"VSS_H37"
$PN"H37"2;
%"GENOA_SP5"
"30","(-5575,3475)","0","pure_quanta","I12";
;
LOCATION"U26"
$SEC"30"
CDS_SEC"30"
PART_TYPE"SMLF"
MATERIAL"IO"
VALUE"SOCKET6096_13568-001"
CDS_LIB"pure_quanta"
CDS_LMAN_SYM_OUTLINE"-400,3050,400,-3050"
NEEDS_NO_SIZE"TRUE"
PART_NUMBER"DGA^6000030";
"VSS_AB66"
$PN"AB66"6;
"VSS_AB64"
$PN"AB64"6;
"VSS_AB61"
$PN"AB61"6;
"VSS_AB59"
$PN"AB59"6;
"VSS_AB57"
$PN"AB57"6;
"VSS_AB54"
$PN"AB54"6;
"VSS_AB51"
$PN"AB51"6;
"VSS_AB48"
$PN"AB48"6;
"VSS_AB45"
$PN"AB45"6;
"VSS_AB42"
$PN"AB42"6;
"VSS_AB39"
$PN"AB39"6;
"VSS_AB37"
$PN"AB37"6;
"VSS_AB34"
$PN"AB34"6;
"VSS_AB31"
$PN"AB31"6;
"VSS_AB28"
$PN"AB28"6;
"VSS_AB25"
$PN"AB25"6;
"VSS_AB22"
$PN"AB22"6;
"VSS_AB19"
$PN"AB19"6;
"VSS_AB17"
$PN"AB17"6;
"VSS_AB15"
$PN"AB15"6;
"VSS_AB12"
$PN"AB12"6;
"VSS_AB10"
$PN"AB10"6;
"VSS_AB8"
$PN"AB8"6;
"VSS_AB5"
$PN"AB5"6;
"VSS_AB3"
$PN"AB3"6;
"VSS_AA75"
$PN"AA75"6;
"VSS_AA70"
$PN"AA70"6;
"VSS_AA68"
$PN"AA68"6;
"VSS_AA65"
$PN"AA65"6;
"VSS_AA63"
$PN"AA63"6;
"VSS_AA61"
$PN"AA61"6;
"VSS_AA58"
$PN"AA58"6;
"VSS_AA56"
$PN"AA56"6;
"VSS_AA45"
$PN"AA45"6;
"VSS_AA41"
$PN"AA41"6;
"VSS_AA40"
$PN"AA40"6;
"VSS_AA36"
$PN"AA36"6;
"VSS_AA35"
$PN"AA35"6;
"VSS_AA34"
$PN"AA34"6;
"VSS_AA31"
$PN"AA31"6;
"VSS_AA20"
$PN"AA20"6;
"VSS_AA18"
$PN"AA18"6;
"VSS_AA15"
$PN"AA15"6;
"VSS_AA13"
$PN"AA13"6;
"VSS_AA11"
$PN"AA11"6;
"VSS_AA8"
$PN"AA8"6;
"VSS_AA6"
$PN"AA6"6;
"VSS_AA4"
$PN"AA4"6;
"VSS_AA1"
$PN"AA1"6;
"VSS_Y73"
$PN"Y73"6;
"VSS_Y68"
$PN"Y68"6;
"VSS_Y66"
$PN"Y66"6;
"VSS_Y61"
$PN"Y61"6;
"VSS_Y59"
$PN"Y59"6;
"VSS_Y54"
$PN"Y54"6;
"VSS_Y53"
$PN"Y53"6;
"VSS_Y52"
$PN"Y52"6;
"VSS_Y51"
$PN"Y51"6;
"VSS_Y50"
$PN"Y50"6;
"VSS_Y49"
$PN"Y49"6;
"VSS_Y48"
$PN"Y48"6;
"VSS_Y45"
$PN"Y45"6;
"VSS_Y44"
$PN"Y44"6;
"VSS_Y43"
$PN"Y43"5;
"VSS_Y42"
$PN"Y42"5;
"VSS_Y39"
$PN"Y39"5;
"VSS_Y37"
$PN"Y37"5;
"VSS_Y34"
$PN"Y34"5;
"VSS_Y33"
$PN"Y33"5;
"VSS_Y32"
$PN"Y32"5;
"VSS_Y31"
$PN"Y31"5;
"VSS_Y28"
$PN"Y28"5;
"VSS_Y27"
$PN"Y27"5;
"VSS_Y26"
$PN"Y26"5;
"VSS_Y25"
$PN"Y25"5;
"VSS_Y24"
$PN"Y24"5;
"VSS_Y23"
$PN"Y23"5;
"VSS_Y22"
$PN"Y22"5;
"VSS_Y17"
$PN"Y17"5;
"VSS_Y15"
$PN"Y15"5;
"VSS_Y10"
$PN"Y10"5;
"VSS_Y8"
$PN"Y8"5;
"VSS_Y3"
$PN"Y3"5;
"VSS_W75"
$PN"W75"5;
"VSS_W72"
$PN"W72"5;
"VSS_W70"
$PN"W70"5;
"VSS_W68"
$PN"W68"5;
"VSS_W65"
$PN"W65"5;
"VSS_W63"
$PN"W63"5;
"VSS_W61"
$PN"W61"5;
"VSS_W58"
$PN"W58"5;
"VSS_W56"
$PN"W56"5;
"VSS_W54"
$PN"W54"5;
"VSS_W51"
$PN"W51"5;
"VSS_W48"
$PN"W48"5;
"VSS_W45"
$PN"W45"5;
"VSS_W42"
$PN"W42"5;
"VSS_W41"
$PN"W41"5;
"VSS_W40"
$PN"W40"5;
"VSS_W36"
$PN"W36"5;
"VSS_W35"
$PN"W35"5;
"VSS_W34"
$PN"W34"5;
"VSS_W28"
$PN"W28"5;
"VSS_W25"
$PN"W25"5;
"VSS_W22"
$PN"W22"5;
"VSS_W20"
$PN"W20"5;
"VSS_W18"
$PN"W18"5;
"VSS_W15"
$PN"W15"5;
"VSS_W13"
$PN"W13"5;
"VSS_W11"
$PN"W11"5;
"VSS_W8"
$PN"W8"5;
"VSS_W6"
$PN"W6"5;
"VSS_W4"
$PN"W4"5;
"VSS_W1"
$PN"W1"5;
"VSS_V73"
$PN"V73"5;
"VSS_V71"
$PN"V71"5;
"VSS_V66"
$PN"V66"5;
"VSS_V64"
$PN"V64"5;
"VSS_V61"
$PN"V61"5;
"VSS_V59"
$PN"V59"5;
"VSS_V57"
$PN"V57"5;
"VSS_V53"
$PN"V53"5;
"VSS_V52"
$PN"V52"5;
"VSS_V51"
$PN"V51"5;
"VSS_V50"
$PN"V50"5;
"VSS_V49"
$PN"V49"5;
"VSS_V48"
$PN"V48"5;
"VSS_V47"
$PN"V47"5;
"VSS_V46"
$PN"V46"5;
"VSS_V45"
$PN"V45"5;
"VSS_V44"
$PN"V44"5;
"VSS_V43"
$PN"V43"5;
"VSS_V42"
$PN"V42"5;
"VSS_V39"
$PN"V39"5;
"VSS_V37"
$PN"V37"5;
"VSS_V34"
$PN"V34"5;
"VSS_V33"
$PN"V33"5;
"VSS_V32"
$PN"V32"5;
"VSS_V31"
$PN"V31"5;
"VSS_V30"
$PN"V30"5;
"VSS_V29"
$PN"V29"5;
"VSS_V28"
$PN"V28"5;
"VSS_V26"
$PN"V26"5;
"VSS_V25"
$PN"V25"5;
"VSS_V24"
$PN"V24"5;
"VSS_V23"
$PN"V23"5;
"VSS_V19"
$PN"V19"5;
"VSS_V17"
$PN"V17"5;
"VSS_V15"
$PN"V15"5;
"VSS_V12"
$PN"V12"5;
"VSS_V10"
$PN"V10"5;
"VSS_V8"
$PN"V8"5;
"VSS_V5"
$PN"V5"5;
"VSS_V3"
$PN"V3"5;
"VSS_U75"
$PN"U75"5;
"VSS_U70"
$PN"U70"5;
"VSS_U68"
$PN"U68"5;
"VSS_U63"
$PN"U63"5;
"VSS_U61"
$PN"U61"5;
"VSS_U56"
$PN"U56"5;
"VSS_U54"
$PN"U54"5;
"VSS_U51"
$PN"U51"5;
"VSS_U48"
$PN"U48"5;
"VSS_U45"
$PN"U45"5;
"VSS_U42"
$PN"U42"5;
"VSS_U34"
$PN"U34"5;
"VSS_U31"
$PN"U31"5;
"VSS_U28"
$PN"U28"5;
"VSS_U25"
$PN"U25"5;
"VSS_U22"
$PN"U22"5;
"VSS_U20"
$PN"U20"5;
"VSS_U15"
$PN"U15"5;
"VSS_U13"
$PN"U13"5;
"VSS_U8"
$PN"U8"5;
"VSS_U6"
$PN"U6"5;
"VSS_U1"
$PN"U1"5;
"VSS_T73"
$PN"T73"5;
"VSS_T71"
$PN"T71"5;
"VSS_T68"
$PN"T68"5;
"VSS_T66"
$PN"T66"5;
"VSS_AD48"
$PN"AD48"6;
"VSS_AD47"
$PN"AD47"6;
"VSS_AD46"
$PN"AD46"6;
"VSS_AD45"
$PN"AD45"6;
"VSS_AD44"
$PN"AD44"6;
"VSS_AD43"
$PN"AD43"6;
"VSS_AD42"
$PN"AD42"6;
"VSS_AD39"
$PN"AD39"6;
"VSS_AD37"
$PN"AD37"6;
"VSS_AD34"
$PN"AD34"6;
"VSS_AD33"
$PN"AD33"6;
"VSS_AD32"
$PN"AD32"6;
"VSS_AD30"
$PN"AD30"6;
"VSS_AD29"
$PN"AD29"6;
"VSS_AD28"
$PN"AD28"6;
"VSS_AD27"
$PN"AD27"6;
"VSS_AD26"
$PN"AD26"6;
"VSS_AD25"
$PN"AD25"6;
"VSS_AD24"
$PN"AD24"6;
"VSS_AD23"
$PN"AD23"6;
"VSS_AD19"
$PN"AD19"6;
"VSS_AD17"
$PN"AD17"6;
"VSS_AD15"
$PN"AD15"6;
"VSS_AD12"
$PN"AD12"6;
"VSS_AD10"
$PN"AD10"6;
"VSS_AD8"
$PN"AD8"6;
"VSS_AD5"
$PN"AD5"6;
"VSS_AD3"
$PN"AD3"6;
"VSS_AC75"
$PN"AC75"6;
"VSS_AC70"
$PN"AC70"6;
"VSS_AC68"
$PN"AC68"6;
"VSS_AC63"
$PN"AC63"6;
"VSS_AC61"
$PN"AC61"6;
"VSS_AC56"
$PN"AC56"6;
"VSS_AC54"
$PN"AC54"6;
"VSS_AC51"
$PN"AC51"6;
"VSS_AC48"
$PN"AC48"6;
"VSS_AC45"
$PN"AC45"6;
"VSS_AC42"
$PN"AC42"6;
"VSS_AC34"
$PN"AC34"6;
"VSS_AC31"
$PN"AC31"6;
"VSS_AC28"
$PN"AC28"6;
"VSS_AC25"
$PN"AC25"6;
"VSS_AC22"
$PN"AC22"6;
"VSS_AC20"
$PN"AC20"6;
"VSS_AC15"
$PN"AC15"6;
"VSS_AC13"
$PN"AC13"6;
"VSS_AC8"
$PN"AC8"6;
"VSS_AC6"
$PN"AC6"6;
"VSS_AC1"
$PN"AC1"6;
"VSS_AB73"
$PN"AB73"6;
"VSS_AB71"
$PN"AB71"6;
"VSS_AB68"
$PN"AB68"6;
%"GENOA_SP5"
"29","(-7050,3450)","0","pure_quanta","I15";
;
LOCATION"U26"
$SEC"29"
CDS_SEC"29"
PART_TYPE"SMLF"
MATERIAL"IO"
VALUE"SOCKET6096_13568-001"
CDS_LIB"pure_quanta"
CDS_LMAN_SYM_OUTLINE"-400,3050,400,-3050"
NEEDS_NO_SIZE"TRUE"
PART_NUMBER"DGA^6000030";
"VSS_R45"
$PN"R45"4;
"VSS_R42"
$PN"R42"4;
"VSS_R41"
$PN"R41"4;
"VSS_R40"
$PN"R40"4;
"VSS_R36"
$PN"R36"4;
"VSS_R35"
$PN"R35"4;
"VSS_R34"
$PN"R34"4;
"VSS_R31"
$PN"R31"4;
"VSS_R28"
$PN"R28"4;
"VSS_R25"
$PN"R25"4;
"VSS_R22"
$PN"R22"4;
"VSS_R20"
$PN"R20"4;
"VSS_R18"
$PN"R18"4;
"VSS_R15"
$PN"R15"4;
"VSS_R13"
$PN"R13"4;
"VSS_R11"
$PN"R11"4;
"VSS_R8"
$PN"R8"4;
"VSS_R6"
$PN"R6"4;
"VSS_R4"
$PN"R4"4;
"VSS_R1"
$PN"R1"4;
"VSS_P73"
$PN"P73"4;
"VSS_P66"
$PN"P66"4;
"VSS_P61"
$PN"P61"4;
"VSS_P59"
$PN"P59"4;
"VSS_P53"
$PN"P53"4;
"VSS_P52"
$PN"P52"4;
"VSS_P51"
$PN"P51"4;
"VSS_P50"
$PN"P50"4;
"VSS_P49"
$PN"P49"4;
"VSS_P48"
$PN"P48"4;
"VSS_P47"
$PN"P47"4;
"VSS_P46"
$PN"P46"4;
"VSS_P45"
$PN"P45"4;
"VSS_P44"
$PN"P44"4;
"VSS_P43"
$PN"P43"4;
"VSS_P42"
$PN"P42"4;
"VSS_P39"
$PN"P39"4;
"VSS_P37"
$PN"P37"4;
"VSS_P34"
$PN"P34"4;
"VSS_P33"
$PN"P33"4;
"VSS_P32"
$PN"P32"4;
"VSS_P31"
$PN"P31"4;
"VSS_P30"
$PN"P30"4;
"VSS_P29"
$PN"P29"4;
"VSS_P28"
$PN"P28"4;
"VSS_P27"
$PN"P27"4;
"VSS_P26"
$PN"P26"4;
"VSS_P24"
$PN"P24"4;
"VSS_P23"
$PN"P23"4;
"VSS_P17"
$PN"P17"4;
"VSS_P15"
$PN"P15"4;
"VSS_P10"
$PN"P10"4;
"VSS_P8"
$PN"P8"4;
"VSS_P3"
$PN"P3"4;
"VSS_N75"
$PN"N75"4;
"VSS_N72"
$PN"N72"4;
"VSS_N70"
$PN"N70"4;
"VSS_N68"
$PN"N68"4;
"VSS_N65"
$PN"N65"4;
"VSS_N63"
$PN"N63"4;
"VSS_N61"
$PN"N61"4;
"VSS_N58"
$PN"N58"4;
"VSS_N56"
$PN"N56"4;
"VSS_N54"
$PN"N54"4;
"VSS_N51"
$PN"N51"4;
"VSS_N48"
$PN"N48"4;
"VSS_N45"
$PN"N45"4;
"VSS_N42"
$PN"N42"4;
"VSS_N34"
$PN"N34"4;
"VSS_N31"
$PN"N31"4;
"VSS_N28"
$PN"N28"4;
"VSS_N25"
$PN"N25"4;
"VSS_N22"
$PN"N22"4;
"VSS_N20"
$PN"N20"4;
"VSS_N18"
$PN"N18"4;
"VSS_N15"
$PN"N15"4;
"VSS_N13"
$PN"N13"4;
"VSS_N11"
$PN"N11"4;
"VSS_N8"
$PN"N8"4;
"VSS_N6"
$PN"N6"4;
"VSS_N4"
$PN"N4"4;
"VSS_N1"
$PN"N1"1;
"VSS_M73"
$PN"M73"1;
"VSS_M71"
$PN"M71"1;
"VSS_M68"
$PN"M68"1;
"VSS_M66"
$PN"M66"1;
"VSS_M64"
$PN"M64"1;
"VSS_M61"
$PN"M61"1;
"VSS_M59"
$PN"M59"1;
"VSS_M57"
$PN"M57"1;
"VSS_M54"
$PN"M54"1;
"VSS_M51"
$PN"M51"1;
"VSS_M48"
$PN"M48"1;
"VSS_M45"
$PN"M45"1;
"VSS_M42"
$PN"M42"1;
"VSS_M39"
$PN"M39"1;
"VSS_M37"
$PN"M37"1;
"VSS_M34"
$PN"M34"1;
"VSS_M31"
$PN"M31"1;
"VSS_M28"
$PN"M28"1;
"VSS_M25"
$PN"M25"1;
"VSS_M22"
$PN"M22"1;
"VSS_M19"
$PN"M19"1;
"VSS_M17"
$PN"M17"1;
"VSS_M15"
$PN"M15"1;
"VSS_M12"
$PN"M12"1;
"VSS_M10"
$PN"M10"1;
"VSS_M8"
$PN"M8"1;
"VSS_M5"
$PN"M5"1;
"VSS_M3"
$PN"M3"1;
"VSS_L75"
$PN"L75"1;
"VSS_L70"
$PN"L70"1;
"VSS_L68"
$PN"L68"1;
"VSS_L63"
$PN"L63"1;
"VSS_L61"
$PN"L61"1;
"VSS_L56"
$PN"L56"1;
"VSS_L54"
$PN"L54"1;
"VSS_L51"
$PN"L51"1;
"VSS_L48"
$PN"L48"1;
"VSS_L45"
$PN"L45"1;
"VSS_L42"
$PN"L42"1;
"VSS_L41"
$PN"L41"1;
"VSS_L40"
$PN"L40"1;
"VSS_L36"
$PN"L36"1;
"VSS_L35"
$PN"L35"1;
"VSS_L34"
$PN"L34"1;
"VSS_L31"
$PN"L31"1;
"VSS_L28"
$PN"L28"1;
"VSS_L25"
$PN"L25"1;
"VSS_L22"
$PN"L22"1;
"VSS_L20"
$PN"L20"1;
"VSS_L15"
$PN"L15"1;
"VSS_L13"
$PN"L13"1;
"VSS_L8"
$PN"L8"1;
"VSS_L6"
$PN"L6"1;
"VSS_L1"
$PN"L1"1;
"VSS_K73"
$PN"K73"1;
"VSS_K71"
$PN"K71"1;
"VSS_K68"
$PN"K68"1;
"VSS_K66"
$PN"K66"1;
"VSS_K64"
$PN"K64"1;
"VSS_K61"
$PN"K61"1;
"VSS_K57"
$PN"K57"1;
"VSS_K53"
$PN"K53"1;
"VSS_K52"
$PN"K52"1;
"VSS_K51"
$PN"K51"1;
"VSS_K50"
$PN"K50"1;
"VSS_K49"
$PN"K49"1;
"VSS_K48"
$PN"K48"1;
"VSS_K47"
$PN"K47"1;
"VSS_K46"
$PN"K46"1;
"VSS_K45"
$PN"K45"1;
"VSS_K44"
$PN"K44"1;
"VSS_K43"
$PN"K43"1;
"VSS_K42"
$PN"K42"1;
"VSS_K39"
$PN"K39"1;
"VSS_K37"
$PN"K37"1;
"VSS_K34"
$PN"K34"1;
"VSS_K33"
$PN"K33"1;
"VSS_K32"
$PN"K32"1;
"VSS_K31"
$PN"K31"1;
"VSS_K30"
$PN"K30"1;
"VSS_K29"
$PN"K29"1;
"VSS_K28"
$PN"K28"1;
"VSS_K27"
$PN"K27"1;
"VSS_K26"
$PN"K26"1;
"VSS_K25"
$PN"K25"1;
"VSS_K24"
$PN"K24"1;
"VSS_K19"
$PN"K19"1;
"VSS_K17"
$PN"K17"1;
"VSS_K15"
$PN"K15"1;
"VSS_K12"
$PN"K12"1;
"VSS_K10"
$PN"K10"1;
"VSS_K8"
$PN"K8"1;
"VSS_K5"
$PN"K5"1;
"VSS_K3"
$PN"K3"1;
"VSS_J75"
$PN"J75"1;
"VSS_J72"
$PN"J72"1;
"VSS_J70"
$PN"J70"1;
"VSS_J68"
$PN"J68"1;
"VSS_J65"
$PN"J65"1;
"VSS_J63"
$PN"J63"1;
"VSS_J61"
$PN"J61"1;
"VSS_J58"
$PN"J58"1;
"VSS_J56"
$PN"J56"1;
"VSS_J54"
$PN"J54"1;
"VSS_J51"
$PN"J51"1;
"VSS_J48"
$PN"J48"1;
"VSS_J45"
$PN"J45"1;
"VSS_J42"
$PN"J42"1;
"VSS_J34"
$PN"J34"1;
"VSS_J31"
$PN"J31"1;
"VSS_J28"
$PN"J28"1;
"VSS_J25"
$PN"J25"1;
"VSS_J22"
$PN"J22"1;
"VSS_J20"
$PN"J20"1;
"VSS_J18"
$PN"J18"1;
"VSS_J15"
$PN"J15"1;
"VSS_T64"
$PN"T64"4;
"VSS_T61"
$PN"T61"4;
"VSS_T59"
$PN"T59"4;
"VSS_T57"
$PN"T57"4;
"VSS_T54"
$PN"T54"4;
"VSS_T51"
$PN"T51"4;
"VSS_T48"
$PN"T48"4;
"VSS_T45"
$PN"T45"4;
"VSS_T42"
$PN"T42"4;
"VSS_T39"
$PN"T39"4;
"VSS_T37"
$PN"T37"4;
"VSS_T34"
$PN"T34"4;
"VSS_T31"
$PN"T31"4;
"VSS_T28"
$PN"T28"4;
"VSS_T25"
$PN"T25"4;
"VSS_T22"
$PN"T22"4;
"VSS_T19"
$PN"T19"4;
"VSS_T17"
$PN"T17"4;
"VSS_T15"
$PN"T15"4;
"VSS_T12"
$PN"T12"4;
"VSS_T10"
$PN"T10"4;
"VSS_T8"
$PN"T8"4;
"VSS_T5"
$PN"T5"4;
"VSS_T3"
$PN"T3"4;
"VSS_R75"
$PN"R75"4;
"VSS_R72"
$PN"R72"4;
"VSS_R70"
$PN"R70"4;
"VSS_R68"
$PN"R68"4;
"VSS_R65"
$PN"R65"4;
"VSS_R63"
$PN"R63"4;
"VSS_R61"
$PN"R61"4;
"VSS_R58"
$PN"R58"4;
"VSS_R56"
$PN"R56"4;
"VSS_R54"
$PN"R54"4;
"VSS_R51"
$PN"R51"4;
"VSS_R48"
$PN"R48"4;
%"UNIVERSAL_GND"
"1","(-9250,375)","0","pure_quanta_power","I18";
;
CDS_LIB"pure_quanta_power"
HDL_POWER"GND";
"A"3;
%"UNIVERSAL_GND"
"1","(-7900,400)","0","pure_quanta_power","I19";
;
CDS_LIB"pure_quanta_power"
HDL_POWER"GND";
"A"2;
%"UNIVERSAL_GND"
"1","(-7725,400)","0","pure_quanta_power","I20";
;
CDS_LIB"pure_quanta_power"
HDL_POWER"GND";
"A"1;
%"UNIVERSAL_GND"
"1","(-6375,425)","0","pure_quanta_power","I21";
;
CDS_LIB"pure_quanta_power"
HDL_POWER"GND";
"A"4;
%"UNIVERSAL_GND"
"1","(-6250,425)","0","pure_quanta_power","I22";
;
CDS_LIB"pure_quanta_power"
HDL_POWER"GND";
"A"5;
%"UNIVERSAL_GND"
"1","(-4900,500)","0","pure_quanta_power","I23";
;
CDS_LIB"pure_quanta_power"
HDL_POWER"GND";
"A"6;
%"UNIVERSAL_GND"
"1","(-4750,500)","0","pure_quanta_power","I24";
;
CDS_LIB"pure_quanta_power"
HDL_POWER"GND";
"A"7;
%"UNIVERSAL_GND"
"1","(-3400,525)","0","pure_quanta_power","I25";
;
CDS_LIB"pure_quanta_power"
HDL_POWER"GND";
"A"8;
%"UNIVERSAL_GND"
"1","(-3250,450)","0","pure_quanta_power","I26";
;
CDS_LIB"pure_quanta_power"
HDL_POWER"GND";
"A"9;
%"UNIVERSAL_GND"
"1","(-1925,475)","0","pure_quanta_power","I27";
;
CDS_LIB"pure_quanta_power"
HDL_POWER"GND";
"A"10;
%"UNIVERSAL_GND"
"1","(-1625,450)","0","pure_quanta_power","I28";
;
CDS_LIB"pure_quanta_power"
HDL_POWER"GND";
"A"11;
%"UNIVERSAL_GND"
"1","(-300,475)","0","pure_quanta_power","I29";
;
CDS_LIB"pure_quanta_power"
HDL_POWER"GND";
"A"12;
%"GENOA_SP5"
"33","(-975,3500)","0","pure_quanta","I3";
;
LOCATION"U26"
$SEC"33"
CDS_SEC"33"
PART_TYPE"SMLF"
MATERIAL"IO"
VALUE"SOCKET6096_13568-001"
CDS_LIB"pure_quanta"
CDS_LMAN_SYM_OUTLINE"-400,3050,400,-3050"
NEEDS_NO_SIZE"TRUE"
PART_NUMBER"DGA^6000030";
"VSS_BL24"
$PN"BL24"12;
"VSS_BL22"
$PN"BL22"12;
"VSS_BL20"
$PN"BL20"12;
"VSS_BL18"
$PN"BL18"12;
"VSS_BL15"
$PN"BL15"12;
"VSS_BL13"
$PN"BL13"12;
"VSS_BL11"
$PN"BL11"12;
"VSS_BL8"
$PN"BL8"12;
"VSS_BL6"
$PN"BL6"12;
"VSS_BL4"
$PN"BL4"12;
"VSS_BL1"
$PN"BL1"12;
"VSS_BK73"
$PN"BK73"12;
"VSS_BK71"
$PN"BK71"12;
"VSS_BK68"
$PN"BK68"12;
"VSS_BK66"
$PN"BK66"12;
"VSS_BK64"
$PN"BK64"12;
"VSS_BK61"
$PN"BK61"12;
"VSS_BK59"
$PN"BK59"12;
"VSS_BK57"
$PN"BK57"12;
"VSS_BK54"
$PN"BK54"12;
"VSS_BK52"
$PN"BK52"12;
"VSS_BK50"
$PN"BK50"12;
"VSS_BK48"
$PN"BK48"12;
"VSS_BK27"
$PN"BK27"12;
"VSS_BK25"
$PN"BK25"12;
"VSS_BK23"
$PN"BK23"12;
"VSS_BK19"
$PN"BK19"12;
"VSS_BK17"
$PN"BK17"12;
"VSS_BK15"
$PN"BK15"12;
"VSS_BK12"
$PN"BK12"12;
"VSS_BK10"
$PN"BK10"12;
"VSS_BK8"
$PN"BK8"12;
"VSS_BK5"
$PN"BK5"12;
"VSS_BK3"
$PN"BK3"12;
"VSS_BJ75"
$PN"BJ75"12;
"VSS_BJ70"
$PN"BJ70"12;
"VSS_BJ68"
$PN"BJ68"12;
"VSS_BJ63"
$PN"BJ63"12;
"VSS_BJ61"
$PN"BJ61"12;
"VSS_BJ56"
$PN"BJ56"12;
"VSS_BJ53"
$PN"BJ53"12;
"VSS_BJ51"
$PN"BJ51"12;
"VSS_BJ49"
$PN"BJ49"12;
"VSS_BJ28"
$PN"BJ28"12;
"VSS_BJ26"
$PN"BJ26"12;
"VSS_BJ24"
$PN"BJ24"12;
"VSS_BJ22"
$PN"BJ22"12;
"VSS_BJ20"
$PN"BJ20"12;
"VSS_BJ15"
$PN"BJ15"12;
"VSS_BJ13"
$PN"BJ13"12;
"VSS_BJ8"
$PN"BJ8"12;
"VSS_BJ6"
$PN"BJ6"12;
"VSS_BJ1"
$PN"BJ1"12;
"VSS_BH73"
$PN"BH73"12;
"VSS_BH71"
$PN"BH71"12;
"VSS_BH68"
$PN"BH68"12;
"VSS_BH66"
$PN"BH66"12;
"VSS_BH64"
$PN"BH64"12;
"VSS_BH61"
$PN"BH61"12;
"VSS_BH59"
$PN"BH59"12;
"VSS_BH57"
$PN"BH57"12;
"VSS_BH54"
$PN"BH54"12;
"VSS_BH52"
$PN"BH52"12;
"VSS_BH50"
$PN"BH50"12;
"VSS_BH49"
$PN"BH49"12;
"VSS_BH28"
$PN"BH28"12;
"VSS_BH26"
$PN"BH26"12;
"VSS_BH24"
$PN"BH24"12;
"VSS_BH22"
$PN"BH22"12;
"VSS_BH19"
$PN"BH19"12;
"VSS_BH17"
$PN"BH17"12;
"VSS_BH15"
$PN"BH15"12;
"VSS_BH12"
$PN"BH12"12;
"VSS_BH10"
$PN"BH10"12;
"VSS_BH8"
$PN"BH8"12;
"VSS_BH5"
$PN"BH5"12;
"VSS_BH3"
$PN"BH3"12;
"VSS_BG75"
$PN"BG75"12;
"VSS_BG72"
$PN"BG72"12;
"VSS_BG70"
$PN"BG70"12;
"VSS_BG68"
$PN"BG68"12;
"VSS_BG65"
$PN"BG65"12;
"VSS_BG63"
$PN"BG63"12;
"VSS_BG61"
$PN"BG61"12;
"VSS_BG58"
$PN"BG58"12;
"VSS_BG56"
$PN"BG56"12;
"VSS_BG53"
$PN"BG53"12;
"VSS_BG51"
$PN"BG51"12;
"VSS_BG49"
$PN"BG49"12;
"VSS_BG27"
$PN"BG27"12;
"VSS_BG25"
$PN"BG25"12;
"VSS_BG23"
$PN"BG23"12;
"VSS_BG20"
$PN"BG20"12;
"VSS_BG18"
$PN"BG18"12;
"VSS_BG15"
$PN"BG15"12;
"VSS_BG13"
$PN"BG13"12;
"VSS_BG11"
$PN"BG11"12;
"VSS_BG8"
$PN"BG8"12;
"VSS_BG6"
$PN"BG6"12;
"VSS_BG4"
$PN"BG4"12;
"VSS_BG1"
$PN"BG1"12;
"VSS_BF73"
$PN"BF73"12;
"VSS_BF68"
$PN"BF68"12;
"VSS_BF66"
$PN"BF66"12;
"VSS_BF61"
$PN"BF61"12;
"VSS_BF59"
$PN"BF59"12;
"VSS_BF54"
$PN"BF54"12;
"VSS_BF52"
$PN"BF52"12;
"VSS_BF50"
$PN"BF50"12;
"VSS_BF49"
$PN"BF49"12;
"VSS_BF28"
$PN"BF28"12;
"VSS_BF26"
$PN"BF26"12;
"VSS_BF24"
$PN"BF24"12;
"VSS_BF22"
$PN"BF22"12;
"VSS_BF19"
$PN"BF19"12;
"VSS_BF17"
$PN"BF17"12;
"VSS_BF15"
$PN"BF15"12;
"VSS_BF12"
$PN"BF12"12;
"VSS_BF10"
$PN"BF10"12;
"VSS_BF8"
$PN"BF8"11;
"VSS_BF5"
$PN"BF5"11;
"VSS_BF3"
$PN"BF3"11;
"VSS_BD73"
$PN"BD73"11;
"VSS_BD71"
$PN"BD71"11;
"VSS_BD68"
$PN"BD68"11;
"VSS_BD66"
$PN"BD66"11;
"VSS_BD64"
$PN"BD64"11;
"VSS_BD61"
$PN"BD61"11;
"VSS_BD59"
$PN"BD59"11;
"VSS_BD57"
$PN"BD57"11;
"VSS_BD53"
$PN"BD53"11;
"VSS_BD51"
$PN"BD51"11;
"VSS_BD49"
$PN"BD49"11;
"VSS_BD27"
$PN"BD27"11;
"VSS_BD25"
$PN"BD25"11;
"VSS_BD23"
$PN"BD23"11;
"VSS_BD17"
$PN"BD17"11;
"VSS_BD15"
$PN"BD15"11;
"VSS_BD10"
$PN"BD10"11;
"VSS_BD8"
$PN"BD8"11;
"VSS_BD3"
$PN"BD3"11;
"VSS_BC75"
$PN"BC75"11;
"VSS_BC72"
$PN"BC72"11;
"VSS_BC70"
$PN"BC70"11;
"VSS_BC68"
$PN"BC68"11;
"VSS_BC65"
$PN"BC65"11;
"VSS_BC63"
$PN"BC63"11;
"VSS_BC61"
$PN"BC61"11;
"VSS_BC58"
$PN"BC58"11;
"VSS_BC56"
$PN"BC56"11;
"VSS_BC53"
$PN"BC53"11;
"VSS_BC51"
$PN"BC51"11;
"VSS_BC50"
$PN"BC50"11;
"VSS_BC49"
$PN"BC49"11;
"VSS_BC28"
$PN"BC28"11;
"VSS_BC26"
$PN"BC26"11;
"VSS_BC24"
$PN"BC24"11;
"VSS_BC22"
$PN"BC22"11;
"VSS_BC20"
$PN"BC20"11;
"VSS_BC18"
$PN"BC18"11;
"VSS_BC15"
$PN"BC15"11;
"VSS_BC13"
$PN"BC13"11;
"VSS_BC11"
$PN"BC11"11;
"VSS_BC8"
$PN"BC8"11;
"VSS_BC6"
$PN"BC6"11;
"VSS_BC4"
$PN"BC4"11;
"VSS_BC1"
$PN"BC1"11;
"VSS_BB73"
$PN"BB73"11;
"VSS_BB71"
$PN"BB71"11;
"VSS_BB68"
$PN"BB68"11;
"VSS_BB66"
$PN"BB66"11;
"VSS_BB64"
$PN"BB64"11;
"VSS_BB61"
$PN"BB61"11;
"VSS_BB59"
$PN"BB59"11;
"VSS_BB57"
$PN"BB57"11;
"VSS_BB54"
$PN"BB54"11;
"VSS_BB52"
$PN"BB52"11;
"VSS_BB50"
$PN"BB50"11;
"VSS_BB48"
$PN"BB48"11;
"VSS_BB27"
$PN"BB27"11;
"VSS_BB25"
$PN"BB25"11;
"VSS_BB23"
$PN"BB23"11;
"VSS_BB19"
$PN"BB19"11;
"VSS_BB17"
$PN"BB17"11;
"VSS_BB15"
$PN"BB15"11;
"VSS_BB12"
$PN"BB12"11;
"VSS_BB10"
$PN"BB10"11;
"VSS_BB8"
$PN"BB8"11;
"VSS_BB5"
$PN"BB5"11;
"VSS_BB3"
$PN"BB3"11;
"VSS_BA75"
$PN"BA75"11;
"VSS_BA70"
$PN"BA70"11;
"VSS_BA68"
$PN"BA68"11;
"VSS_BA63"
$PN"BA63"11;
"VSS_BA61"
$PN"BA61"11;
"VSS_BA56"
$PN"BA56"11;
"VSS_BA53"
$PN"BA53"11;
"VSS_BA51"
$PN"BA51"11;
"VSS_BA49"
$PN"BA49"11;
"VSS_BA28"
$PN"BA28"11;
"VSS_BA26"
$PN"BA26"11;
"VSS_BA24"
$PN"BA24"11;
"VSS_BA22"
$PN"BA22"11;
"VSS_BA20"
$PN"BA20"11;
"VSS_BA15"
$PN"BA15"11;
"VSS_BA13"
$PN"BA13"11;
"VSS_BA8"
$PN"BA8"11;
"VSS_BA6"
$PN"BA6"11;
"VSS_BA1"
$PN"BA1"11;
"VSS_AY73"
$PN"AY73"11;
"VSS_AY71"
$PN"AY71"11;
"VSS_AY68"
$PN"AY68"11;
"VSS_AY66"
$PN"AY66"11;
"VSS_AY64"
$PN"AY64"11;
"VSS_AY61"
$PN"AY61"11;
"VSS_AY59"
$PN"AY59"11;
"VSS_AY57"
$PN"AY57"11;
"VSS_AY54"
$PN"AY54"11;
"VSS_AY52"
$PN"AY52"11;
"VSS_AY50"
$PN"AY50"11;
"VSS_AY48"
$PN"AY48"11;
"VSS_AY27"
$PN"AY27"11;
"VSS_AY25"
$PN"AY25"11;
"VSS_AY23"
$PN"AY23"11;
"VSS_AY19"
$PN"AY19"11;
"VSS_AY17"
$PN"AY17"11;
"VSS_AY15"
$PN"AY15"11;
"VSS_AY12"
$PN"AY12"11;
"VSS_AY10"
$PN"AY10"11;
"VSS_AY8"
$PN"AY8"11;
"VSS_AY5"
$PN"AY5"11;
"VSS_AY3"
$PN"AY3"11;
"VSS_AW75"
$PN"AW75"11;
"VSS_AW72"
$PN"AW72"11;
"VSS_AW70"
$PN"AW70"11;
"VSS_AW68"
$PN"AW68"11;
"VSS_AW65"
$PN"AW65"11;
"VSS_AW63"
$PN"AW63"11;
%"GENOA_SP5"
"32","(-2600,3500)","0","pure_quanta","I6";
;
LOCATION"U26"
$SEC"32"
CDS_SEC"32"
PART_TYPE"SMLF"
MATERIAL"IO"
VALUE"SOCKET6096_13568-001"
CDS_LIB"pure_quanta"
CDS_LMAN_SYM_OUTLINE"-400,3050,400,-3050"
NEEDS_NO_SIZE"TRUE"
PART_NUMBER"DGA^6000030";
"VSS_AW61"
$PN"AW61"10;
"VSS_AW58"
$PN"AW58"10;
"VSS_AW56"
$PN"AW56"10;
"VSS_AW53"
$PN"AW53"10;
"VSS_AW51"
$PN"AW51"10;
"VSS_AW49"
$PN"AW49"10;
"VSS_AW28"
$PN"AW28"10;
"VSS_AW26"
$PN"AW26"10;
"VSS_AW24"
$PN"AW24"10;
"VSS_AW22"
$PN"AW22"10;
"VSS_AW20"
$PN"AW20"10;
"VSS_AW18"
$PN"AW18"10;
"VSS_AW15"
$PN"AW15"10;
"VSS_AW13"
$PN"AW13"10;
"VSS_AW11"
$PN"AW11"10;
"VSS_AW8"
$PN"AW8"10;
"VSS_AW6"
$PN"AW6"10;
"VSS_AW4"
$PN"AW4"10;
"VSS_AW1"
$PN"AW1"10;
"VSS_AV73"
$PN"AV73"10;
"VSS_AV68"
$PN"AV68"10;
"VSS_AV66"
$PN"AV66"10;
"VSS_AV61"
$PN"AV61"10;
"VSS_AV59"
$PN"AV59"10;
"VSS_AV54"
$PN"AV54"10;
"VSS_AV52"
$PN"AV52"10;
"VSS_AV50"
$PN"AV50"10;
"VSS_AV48"
$PN"AV48"10;
"VSS_AV46"
$PN"AV46"10;
"VSS_AV44"
$PN"AV44"10;
"VSS_AV42"
$PN"AV42"10;
"VSS_AV40"
$PN"AV40"10;
"VSS_AV37"
$PN"AV37"10;
"VSS_AV35"
$PN"AV35"10;
"VSS_AV33"
$PN"AV33"10;
"VSS_AV31"
$PN"AV31"10;
"VSS_AV29"
$PN"AV29"10;
"VSS_AV27"
$PN"AV27"10;
"VSS_AV25"
$PN"AV25"10;
"VSS_AV23"
$PN"AV23"10;
"VSS_AV17"
$PN"AV17"10;
"VSS_AV15"
$PN"AV15"10;
"VSS_AV10"
$PN"AV10"10;
"VSS_AV8"
$PN"AV8"10;
"VSS_AV3"
$PN"AV3"10;
"VSS_AU75"
$PN"AU75"10;
"VSS_AU73"
$PN"AU73"10;
"VSS_AU72"
$PN"AU72"10;
"VSS_AU70"
$PN"AU70"10;
"VSS_AU68"
$PN"AU68"10;
"VSS_AU65"
$PN"AU65"10;
"VSS_AU63"
$PN"AU63"10;
"VSS_AU61"
$PN"AU61"10;
"VSS_AU58"
$PN"AU58"10;
"VSS_AU56"
$PN"AU56"10;
"VSS_AU53"
$PN"AU53"10;
"VSS_AU51"
$PN"AU51"10;
"VSS_AU49"
$PN"AU49"10;
"VSS_AU47"
$PN"AU47"10;
"VSS_AU45"
$PN"AU45"10;
"VSS_AU43"
$PN"AU43"10;
"VSS_AU41"
$PN"AU41"10;
"VSS_AU36"
$PN"AU36"10;
"VSS_AU34"
$PN"AU34"10;
"VSS_AU32"
$PN"AU32"10;
"VSS_AU30"
$PN"AU30"10;
"VSS_AU28"
$PN"AU28"10;
"VSS_AU26"
$PN"AU26"10;
"VSS_AU24"
$PN"AU24"10;
"VSS_AU22"
$PN"AU22"10;
"VSS_AU20"
$PN"AU20"10;
"VSS_AU18"
$PN"AU18"10;
"VSS_AU15"
$PN"AU15"10;
"VSS_AU13"
$PN"AU13"10;
"VSS_AU11"
$PN"AU11"10;
"VSS_AU8"
$PN"AU8"10;
"VSS_AU6"
$PN"AU6"10;
"VSS_AU4"
$PN"AU4"10;
"VSS_AU3"
$PN"AU3"10;
"VSS_AU1"
$PN"AU1"10;
"VSS_AT73"
$PN"AT73"10;
"VSS_AT72"
$PN"AT72"10;
"VSS_AT71"
$PN"AT71"10;
"VSS_AT70"
$PN"AT70"10;
"VSS_AT68"
$PN"AT68"10;
"VSS_AT67"
$PN"AT67"10;
"VSS_AT66"
$PN"AT66"10;
"VSS_AT64"
$PN"AT64"10;
"VSS_AT63"
$PN"AT63"10;
"VSS_AT61"
$PN"AT61"10;
"VSS_AT60"
$PN"AT60"10;
"VSS_AT59"
$PN"AT59"10;
"VSS_AT57"
$PN"AT57"10;
"VSS_AT56"
$PN"AT56"10;
"VSS_AT54"
$PN"AT54"10;
"VSS_AT52"
$PN"AT52"10;
"VSS_AT50"
$PN"AT50"10;
"VSS_AT48"
$PN"AT48"10;
"VSS_AT46"
$PN"AT46"10;
"VSS_AT44"
$PN"AT44"10;
"VSS_AT42"
$PN"AT42"10;
"VSS_AT40"
$PN"AT40"10;
"VSS_AT37"
$PN"AT37"10;
"VSS_AT35"
$PN"AT35"10;
"VSS_AT33"
$PN"AT33"10;
"VSS_AT31"
$PN"AT31"10;
"VSS_AT29"
$PN"AT29"10;
"VSS_AT27"
$PN"AT27"10;
"VSS_AT25"
$PN"AT25"10;
"VSS_AT23"
$PN"AT23"10;
"VSS_AT20"
$PN"AT20"10;
"VSS_AT19"
$PN"AT19"10;
"VSS_AT17"
$PN"AT17"10;
"VSS_AT16"
$PN"AT16"10;
"VSS_AT15"
$PN"AT15"10;
"VSS_AT13"
$PN"AT13"10;
"VSS_AT12"
$PN"AT12"10;
"VSS_AT10"
$PN"AT10"10;
"VSS_AT9"
$PN"AT9"10;
"VSS_AT8"
$PN"AT8"9;
"VSS_AT6"
$PN"AT6"9;
"VSS_AT5"
$PN"AT5"9;
"VSS_AT4"
$PN"AT4"9;
"VSS_AT3"
$PN"AT3"9;
"VSS_AR75"
$PN"AR75"9;
"VSS_AR71"
$PN"AR71"9;
"VSS_AR70"
$PN"AR70"9;
"VSS_AR68"
$PN"AR68"9;
"VSS_AR67"
$PN"AR67"9;
"VSS_AR64"
$PN"AR64"9;
"VSS_AR63"
$PN"AR63"9;
"VSS_AR61"
$PN"AR61"9;
"VSS_AR60"
$PN"AR60"9;
"VSS_AR57"
$PN"AR57"9;
"VSS_AR56"
$PN"AR56"9;
"VSS_AR53"
$PN"AR53"9;
"VSS_AR51"
$PN"AR51"9;
"VSS_AR49"
$PN"AR49"9;
"VSS_AR47"
$PN"AR47"9;
"VSS_AR45"
$PN"AR45"9;
"VSS_AR43"
$PN"AR43"9;
"VSS_AR41"
$PN"AR41"9;
"VSS_AR36"
$PN"AR36"9;
"VSS_AR34"
$PN"AR34"9;
"VSS_AR32"
$PN"AR32"9;
"VSS_AR30"
$PN"AR30"9;
"VSS_AR28"
$PN"AR28"9;
"VSS_AR26"
$PN"AR26"9;
"VSS_AR24"
$PN"AR24"9;
"VSS_AR22"
$PN"AR22"9;
"VSS_AR20"
$PN"AR20"9;
"VSS_AR19"
$PN"AR19"9;
"VSS_AR16"
$PN"AR16"9;
"VSS_AR15"
$PN"AR15"9;
"VSS_AR13"
$PN"AR13"9;
"VSS_AR12"
$PN"AR12"9;
"VSS_AR9"
$PN"AR9"9;
"VSS_AR8"
$PN"AR8"9;
"VSS_AR6"
$PN"AR6"9;
"VSS_AR5"
$PN"AR5"9;
"VSS_AR1"
$PN"AR1"9;
"VSS_AP73"
$PN"AP73"9;
"VSS_AP71"
$PN"AP71"9;
"VSS_AP68"
$PN"AP68"9;
"VSS_AP66"
$PN"AP66"9;
"VSS_AP64"
$PN"AP64"9;
"VSS_AP61"
$PN"AP61"9;
"VSS_AP59"
$PN"AP59"9;
"VSS_AP57"
$PN"AP57"9;
"VSS_AP54"
$PN"AP54"9;
"VSS_AP51"
$PN"AP51"9;
"VSS_AP48"
$PN"AP48"9;
"VSS_AP45"
$PN"AP45"9;
"VSS_AP42"
$PN"AP42"9;
"VSS_AP39"
$PN"AP39"9;
"VSS_AP37"
$PN"AP37"9;
"VSS_AP34"
$PN"AP34"9;
"VSS_AP31"
$PN"AP31"9;
"VSS_AP28"
$PN"AP28"9;
"VSS_AP25"
$PN"AP25"9;
"VSS_AP22"
$PN"AP22"9;
"VSS_AP19"
$PN"AP19"9;
"VSS_AP17"
$PN"AP17"9;
"VSS_AP15"
$PN"AP15"9;
"VSS_AP12"
$PN"AP12"9;
"VSS_AP10"
$PN"AP10"9;
"VSS_AP8"
$PN"AP8"9;
"VSS_AP5"
$PN"AP5"9;
"VSS_AP3"
$PN"AP3"9;
"VSS_AN75"
$PN"AN75"9;
"VSS_AN72"
$PN"AN72"9;
"VSS_AN70"
$PN"AN70"9;
"VSS_AN68"
$PN"AN68"9;
"VSS_AN65"
$PN"AN65"9;
"VSS_AN63"
$PN"AN63"9;
"VSS_AN61"
$PN"AN61"9;
"VSS_AN58"
$PN"AN58"9;
"VSS_AN56"
$PN"AN56"9;
"VSS_AN54"
$PN"AN54"9;
"VSS_AN51"
$PN"AN51"9;
"VSS_AN48"
$PN"AN48"9;
"VSS_AN45"
$PN"AN45"9;
"VSS_AN42"
$PN"AN42"9;
"VSS_AN41"
$PN"AN41"9;
"VSS_AN40"
$PN"AN40"9;
"VSS_AN36"
$PN"AN36"9;
"VSS_AN35"
$PN"AN35"9;
"VSS_AN34"
$PN"AN34"9;
"VSS_AN31"
$PN"AN31"9;
"VSS_AN28"
$PN"AN28"9;
"VSS_AN25"
$PN"AN25"9;
"VSS_AN22"
$PN"AN22"9;
"VSS_AN18"
$PN"AN18"9;
"VSS_AN15"
$PN"AN15"9;
"VSS_AN13"
$PN"AN13"9;
"VSS_AN11"
$PN"AN11"9;
"VSS_AN8"
$PN"AN8"9;
"VSS_AN6"
$PN"AN6"9;
"VSS_AN4"
$PN"AN4"9;
"VSS_AN1"
$PN"AN1"9;
"VSS_AM73"
$PN"AM73"9;
"VSS_AM68"
$PN"AM68"9;
"VSS_AM66"
$PN"AM66"9;
"VSS_AM61"
$PN"AM61"9;
"VSS_AM59"
$PN"AM59"9;
"VSS_AM53"
$PN"AM53"9;
"VSS_AM52"
$PN"AM52"9;
"VSS_AM51"
$PN"AM51"9;
"VSS_AM50"
$PN"AM50"9;
"VSS_AM49"
$PN"AM49"9;
"VSS_AM48"
$PN"AM48"9;
"VSS_AM47"
$PN"AM47"9;
"VSS_AM46"
$PN"AM46"9;
"VSS_AM45"
$PN"AM45"9;
"VSS_AM44"
$PN"AM44"9;
"VSS_AM43"
$PN"AM43"9;
"VSS_AM42"
$PN"AM42"9;
%"GENOA_SP5"
"31","(-4075,3500)","0","pure_quanta","I9";
;
LOCATION"U26"
$SEC"31"
CDS_SEC"31"
PART_TYPE"SMLF"
MATERIAL"IO"
VALUE"SOCKET6096_13568-001"
CDS_LIB"pure_quanta"
CDS_LMAN_SYM_OUTLINE"-400,3050,400,-3050"
NEEDS_NO_SIZE"TRUE"
PART_NUMBER"DGA^6000030";
"VSS_AK8"
$PN"AK8"8;
"VSS_AK5"
$PN"AK5"8;
"VSS_AK3"
$PN"AK3"8;
"VSS_AJ75"
$PN"AJ75"8;
"VSS_AJ70"
$PN"AJ70"8;
"VSS_AJ68"
$PN"AJ68"8;
"VSS_AJ63"
$PN"AJ63"8;
"VSS_AJ61"
$PN"AJ61"8;
"VSS_AJ56"
$PN"AJ56"8;
"VSS_AJ54"
$PN"AJ54"8;
"VSS_AJ51"
$PN"AJ51"8;
"VSS_AJ48"
$PN"AJ48"8;
"VSS_AJ45"
$PN"AJ45"8;
"VSS_AJ42"
$PN"AJ42"8;
"VSS_AJ41"
$PN"AJ41"8;
"VSS_AJ40"
$PN"AJ40"8;
"VSS_AJ36"
$PN"AJ36"8;
"VSS_AJ35"
$PN"AJ35"8;
"VSS_AJ34"
$PN"AJ34"8;
"VSS_AJ31"
$PN"AJ31"8;
"VSS_AJ28"
$PN"AJ28"8;
"VSS_AJ25"
$PN"AJ25"8;
"VSS_AJ22"
$PN"AJ22"8;
"VSS_AJ20"
$PN"AJ20"8;
"VSS_AJ15"
$PN"AJ15"8;
"VSS_AJ8"
$PN"AJ8"8;
"VSS_AJ6"
$PN"AJ6"8;
"VSS_AJ1"
$PN"AJ1"8;
"VSS_AH73"
$PN"AH73"8;
"VSS_AH71"
$PN"AH71"8;
"VSS_AH68"
$PN"AH68"8;
"VSS_AH66"
$PN"AH66"8;
"VSS_AH64"
$PN"AH64"8;
"VSS_AH61"
$PN"AH61"8;
"VSS_AH59"
$PN"AH59"8;
"VSS_AH57"
$PN"AH57"8;
"VSS_AH53"
$PN"AH53"8;
"VSS_AH52"
$PN"AH52"8;
"VSS_AH51"
$PN"AH51"8;
"VSS_AH50"
$PN"AH50"8;
"VSS_AH49"
$PN"AH49"8;
"VSS_AH48"
$PN"AH48"8;
"VSS_AH47"
$PN"AH47"8;
"VSS_AH46"
$PN"AH46"8;
"VSS_AH45"
$PN"AH45"8;
"VSS_AH44"
$PN"AH44"8;
"VSS_AH43"
$PN"AH43"7;
"VSS_AH42"
$PN"AH42"7;
"VSS_AH39"
$PN"AH39"7;
"VSS_AH37"
$PN"AH37"7;
"VSS_AH34"
$PN"AH34"7;
"VSS_AH32"
$PN"AH32"7;
"VSS_AH31"
$PN"AH31"7;
"VSS_AH30"
$PN"AH30"7;
"VSS_AH29"
$PN"AH29"7;
"VSS_AH28"
$PN"AH28"7;
"VSS_AH27"
$PN"AH27"7;
"VSS_AH26"
$PN"AH26"7;
"VSS_AH25"
$PN"AH25"7;
"VSS_AH24"
$PN"AH24"7;
"VSS_AH23"
$PN"AH23"7;
"VSS_AH19"
$PN"AH19"7;
"VSS_AH17"
$PN"AH17"7;
"VSS_AH15"
$PN"AH15"7;
"VSS_AH12"
$PN"AH12"7;
"VSS_AH10"
$PN"AH10"7;
"VSS_AH8"
$PN"AH8"7;
"VSS_AH5"
$PN"AH5"7;
"VSS_AH3"
$PN"AH3"7;
"VSS_AG75"
$PN"AG75"7;
"VSS_AG72"
$PN"AG72"7;
"VSS_AG70"
$PN"AG70"7;
"VSS_AG68"
$PN"AG68"7;
"VSS_AG65"
$PN"AG65"7;
"VSS_AG63"
$PN"AG63"7;
"VSS_AG61"
$PN"AG61"7;
"VSS_AG58"
$PN"AG58"7;
"VSS_AG56"
$PN"AG56"7;
"VSS_AG54"
$PN"AG54"7;
"VSS_AG51"
$PN"AG51"7;
"VSS_AG48"
$PN"AG48"7;
"VSS_AG45"
$PN"AG45"7;
"VSS_AG42"
$PN"AG42"7;
"VSS_AG34"
$PN"AG34"7;
"VSS_AG31"
$PN"AG31"7;
"VSS_AG28"
$PN"AG28"7;
"VSS_AG25"
$PN"AG25"7;
"VSS_AG22"
$PN"AG22"7;
"VSS_AG20"
$PN"AG20"7;
"VSS_AG18"
$PN"AG18"7;
"VSS_AG15"
$PN"AG15"7;
"VSS_AG13"
$PN"AG13"7;
"VSS_AG11"
$PN"AG11"7;
"VSS_AG8"
$PN"AG8"7;
"VSS_AG6"
$PN"AG6"7;
"VSS_AG4"
$PN"AG4"7;
"VSS_AG1"
$PN"AG1"7;
"VSS_AF73"
$PN"AF73"7;
"VSS_AF68"
$PN"AF68"7;
"VSS_AF66"
$PN"AF66"7;
"VSS_AF61"
$PN"AF61"7;
"VSS_AF59"
$PN"AF59"7;
"VSS_AF54"
$PN"AF54"7;
"VSS_AF51"
$PN"AF51"7;
"VSS_AF48"
$PN"AF48"7;
"VSS_AF45"
$PN"AF45"7;
"VSS_AF42"
$PN"AF42"7;
"VSS_AF39"
$PN"AF39"7;
"VSS_AF37"
$PN"AF37"7;
"VSS_AF34"
$PN"AF34"7;
"VSS_AF31"
$PN"AF31"7;
"VSS_AF28"
$PN"AF28"7;
"VSS_AF25"
$PN"AF25"7;
"VSS_AF22"
$PN"AF22"7;
"VSS_AF17"
$PN"AF17"7;
"VSS_AF15"
$PN"AF15"7;
"VSS_AF10"
$PN"AF10"7;
"VSS_AF8"
$PN"AF8"7;
"VSS_AF3"
$PN"AF3"7;
"VSS_AE75"
$PN"AE75"7;
"VSS_AE72"
$PN"AE72"7;
"VSS_AE70"
$PN"AE70"7;
"VSS_AE68"
$PN"AE68"7;
"VSS_AE65"
$PN"AE65"7;
"VSS_AE63"
$PN"AE63"7;
"VSS_AE61"
$PN"AE61"7;
"VSS_AE58"
$PN"AE58"7;
"VSS_AE56"
$PN"AE56"7;
"VSS_AE54"
$PN"AE54"7;
"VSS_AE51"
$PN"AE51"7;
"VSS_AE48"
$PN"AE48"7;
"VSS_AE45"
$PN"AE45"7;
"VSS_AE42"
$PN"AE42"7;
"VSS_AE41"
$PN"AE41"7;
"VSS_AE40"
$PN"AE40"7;
"VSS_AE36"
$PN"AE36"7;
"VSS_AE35"
$PN"AE35"7;
"VSS_AE34"
$PN"AE34"7;
"VSS_AE31"
$PN"AE31"7;
"VSS_AE28"
$PN"AE28"7;
"VSS_AE25"
$PN"AE25"7;
"VSS_AE22"
$PN"AE22"7;
"VSS_AE20"
$PN"AE20"7;
"VSS_AE18"
$PN"AE18"7;
"VSS_AE15"
$PN"AE15"7;
"VSS_AE13"
$PN"AE13"7;
"VSS_AE11"
$PN"AE11"7;
"VSS_AE8"
$PN"AE8"7;
"VSS_AE6"
$PN"AE6"7;
"VSS_AE1"
$PN"AE1"7;
"VSS_AD73"
$PN"AD73"7;
"VSS_AD71"
$PN"AD71"7;
"VSS_AD68"
$PN"AD68"7;
"VSS_AD66"
$PN"AD66"7;
"VSS_AD64"
$PN"AD64"7;
"VSS_AD61"
$PN"AD61"7;
"VSS_AD59"
$PN"AD59"7;
"VSS_AD57"
$PN"AD57"7;
"VSS_AD53"
$PN"AD53"7;
"VSS_AD52"
$PN"AD52"7;
"VSS_AD51"
$PN"AD51"7;
"VSS_AD50"
$PN"AD50"7;
"VSS_AD49"
$PN"AD49"7;
"VSS_AM39"
$PN"AM39"8;
"VSS_AM34"
$PN"AM34"8;
"VSS_AM33"
$PN"AM33"8;
"VSS_AM32"
$PN"AM32"8;
"VSS_AM31"
$PN"AM31"8;
"VSS_AM30"
$PN"AM30"8;
"VSS_AM29"
$PN"AM29"8;
"VSS_AM28"
$PN"AM28"8;
"VSS_AM27"
$PN"AM27"8;
"VSS_AM26"
$PN"AM26"8;
"VSS_AM25"
$PN"AM25"8;
"VSS_AM24"
$PN"AM24"8;
"VSS_AM23"
$PN"AM23"8;
"VSS_AM17"
$PN"AM17"8;
"VSS_AM15"
$PN"AM15"8;
"VSS_AM10"
$PN"AM10"8;
"VSS_AM8"
$PN"AM8"8;
"VSS_AM3"
$PN"AM3"8;
"VSS_AL75"
$PN"AL75"8;
"VSS_AL72"
$PN"AL72"8;
"VSS_AL70"
$PN"AL70"8;
"VSS_AL68"
$PN"AL68"8;
"VSS_AL65"
$PN"AL65"8;
"VSS_AL63"
$PN"AL63"8;
"VSS_AL61"
$PN"AL61"8;
"VSS_AL58"
$PN"AL58"8;
"VSS_AL56"
$PN"AL56"8;
"VSS_AL54"
$PN"AL54"8;
"VSS_AL51"
$PN"AL51"8;
"VSS_AL48"
$PN"AL48"8;
"VSS_AL45"
$PN"AL45"8;
"VSS_AL42"
$PN"AL42"8;
"VSS_AL34"
$PN"AL34"8;
"VSS_AL31"
$PN"AL31"8;
"VSS_AL28"
$PN"AL28"8;
"VSS_AL25"
$PN"AL25"8;
"VSS_AL22"
$PN"AL22"8;
"VSS_AL20"
$PN"AL20"8;
"VSS_AL18"
$PN"AL18"8;
"VSS_AL15"
$PN"AL15"8;
"VSS_AL13"
$PN"AL13"8;
"VSS_AL11"
$PN"AL11"8;
"VSS_AL8"
$PN"AL8"8;
"VSS_AL6"
$PN"AL6"8;
"VSS_AL4"
$PN"AL4"8;
"VSS_AL1"
$PN"AL1"8;
"VSS_AK73"
$PN"AK73"8;
"VSS_AK71"
$PN"AK71"8;
"VSS_AK68"
$PN"AK68"8;
"VSS_AK66"
$PN"AK66"8;
"VSS_AK64"
$PN"AK64"8;
"VSS_AK61"
$PN"AK61"8;
"VSS_AK59"
$PN"AK59"8;
"VSS_AK57"
$PN"AK57"8;
"VSS_AK54"
$PN"AK54"8;
"VSS_AK51"
$PN"AK51"8;
"VSS_AK48"
$PN"AK48"8;
"VSS_AK45"
$PN"AK45"8;
"VSS_AK42"
$PN"AK42"8;
"VSS_AK39"
$PN"AK39"8;
"VSS_AK37"
$PN"AK37"8;
"VSS_AK34"
$PN"AK34"8;
"VSS_AK31"
$PN"AK31"8;
"VSS_AK28"
$PN"AK28"8;
"VSS_AK25"
$PN"AK25"8;
"VSS_AK22"
$PN"AK22"8;
"VSS_AK19"
$PN"AK19"8;
"VSS_AK17"
$PN"AK17"8;
"VSS_AK15"
$PN"AK15"8;
"VSS_AK12"
$PN"AK12"8;
"VSS_AK10"
$PN"AK10"8;
END.
